# BASEBOARD_FAB2 (Tioga Pass) — schematic netlist excerpt (pin names and nets, part order shuffled) for the footprints in the layout excerpt that follows; sources: Cadence DE-HDL packaged netlist, KiCad conversion of Wiwynn_Tioga_Pass_MB.brd

R9A16  RES  2.21K 1% CHIP  pkg 0402  page 135 : A = PU_KEY_CONN_PIN2_R ; B = P3V3_STBY
C1E16  CAP_A  0.1UF 16V 10% X7R  pkg 0402V  page 195 : A = P12V_PSU ; B = GND
CT5  CAP  1000PF 50V 10% X7R  pkg 0402LF  page 202 : A = VR_PVCCIN_CPU0_PHASE2 ; B = VR_PVCCIN_CPU0_PHASE2_RC

(kicad_pcb
	(version 20260206)
	(generator "pcbnew")
	(generator_version "10.0")
	(general
		(thickness 1.6)
		(legacy_teardrops no)
	)
	(paper "A4")
	(title_block
		(title "Wiwynn_Tioga_Pass_MB.brd")
		(comment 1 "Tioga Pass / footprints 2039-2041 of 4770")
	)
	(layers
		(0 "F.Cu" signal "TOP")
		(4 "In1.Cu" signal "L2GND")
		(6 "In2.Cu" signal "L3")
		(8 "In3.Cu" signal "L4GND")
		(10 "In4.Cu" signal "L5")
		(12 "In5.Cu" signal "L6GND")
		(14 "In6.Cu" signal "L7VCC")
		(16 "In7.Cu" signal "L8VCC")
		(18 "In8.Cu" signal "L9GND")
		(20 "In9.Cu" signal "L10")
		(22 "In10.Cu" signal "L11GND")
		(24 "In11.Cu" signal "L12")
		(26 "In12.Cu" signal "L13GND")
		(2 "B.Cu" signal "BOTTOM")
		(9 "F.Adhes" user "F.Adhesive")
		(11 "B.Adhes" user "B.Adhesive")
		(13 "F.Paste" user "Package Geometry/Pastemask Top")
		(15 "B.Paste" user "Package Geometry/Pastemask Bottom")
		(5 "F.SilkS" user "Ref Des/Silkscreen Top")
		(7 "B.SilkS" user "Ref Des/Silkscreen Bottom")
		(1 "F.Mask" user "Board Geometry/Soldermask Top")
		(3 "B.Mask" user "Board Geometry/Soldermask Bottom")
		(17 "Dwgs.User" user "User.Drawings")
		(19 "Cmts.User" user "User.Comments")
		(21 "Eco1.User" user "User.Eco1")
		(23 "Eco2.User" user "User.Eco2")
		(25 "Edge.Cuts" user "Board Geometry/Outline")
		(27 "Margin" user)
		(31 "F.CrtYd" user "Package Geometry/Place Bound Top")
		(29 "B.CrtYd" user "Package Geometry/Place Bound Bottom")
		(35 "F.Fab" user "Ref Des/Assembly Top")
		(33 "B.Fab" user "Ref Des/Assembly Bottom")
	)
	(footprint ""
		(layer "F.Cu")
		(at 13.462 -51.816 90)
		(property "Reference" "C1E16"
			(at 0 0 90)
			(layer "F.SilkS")
			(hide yes)
			(effects
				(font
					(size 1.27 1.27)
				)
			)
		)
		(property "Value" ""
			(at 0 0 90)
			(layer "F.Fab")
			(effects
				(font
					(size 1.27 1.27)
				)
			)
		)
		(duplicate_pad_numbers_are_jumpers no)
		(fp_rect
			(start -0.3048 -0.1016)
			(end 0.3048 0.9906)
			(stroke
				(width 0)
				(type default)
			)
			(fill no)
			(layer "F.CrtYd")
		)
		(fp_line
			(start 0.3048 -0.1016)
			(end -0.3048 -0.1016)
			(stroke
				(width 0.1)
				(type default)
			)
			(layer "F.Fab")
		)
		(fp_line
			(start -0.3048 -0.1016)
			(end -0.3048 0.9906)
			(stroke
				(width 0.1)
				(type default)
			)
			(layer "F.Fab")
		)
		(fp_line
			(start 0.3048 0.9906)
			(end 0.3048 -0.1016)
			(stroke
				(width 0.1)
				(type default)
			)
			(layer "F.Fab")
		)
		(fp_line
			(start -0.3048 0.9906)
			(end 0.3048 0.9906)
			(stroke
				(width 0.1)
				(type default)
			)
			(layer "F.Fab")
		)
		(pad "1" smd rect
			(at 0 0 90)
			(size 0.508 0.508)
			(layers "F.Cu" "F.Mask" "F.Paste")
			(net "P12V_PSU")
		)
		(pad "2" smd rect
			(at 0 0.889 90)
			(size 0.508 0.508)
			(layers "F.Cu" "F.Mask" "F.Paste")
			(net "GND")
		)
		(zone
			(layer "F.Cu")
			(hatch none 0.5)
			(connect_pads
				(clearance 0)
			)
			(min_thickness 0.25)
			(keepout
				(tracks allowed)
				(vias not_allowed)
				(pads allowed)
				(copperpour not_allowed)
				(footprints allowed)
			)
			(placement
				(enabled no)
				(sheetname "")
			)
			(fill
				(thermal_gap 0.5)
				(thermal_bridge_width 0.5)
				(island_removal_mode 0)
			)
			(polygon
				(pts
					(xy 13.716 -51.562) (xy 14.097 -51.562) (xy 14.097 -52.07) (xy 13.716 -52.07)
				)
			)
		)
		(zone
			(layer "F.Cu")
			(hatch none 0.5)
			(connect_pads
				(clearance 0)
			)
			(min_thickness 0.25)
			(keepout
				(tracks not_allowed)
				(vias allowed)
				(pads allowed)
				(copperpour not_allowed)
				(footprints allowed)
			)
			(placement
				(enabled no)
				(sheetname "")
			)
			(fill
				(thermal_gap 0.5)
				(thermal_bridge_width 0.5)
				(island_removal_mode 0)
			)
			(polygon
				(pts
					(xy 13.716 -51.562) (xy 14.097 -51.562) (xy 14.097 -52.07) (xy 13.716 -52.07)
				)
			)
		)
	)
	(footprint ""
		(layer "F.Cu")
		(at 204.8764 -61.214 -90)
		(property "Reference" "CT5"
			(at -0.8382 -0.67818 270)
			(unlocked yes)
			(layer "F.SilkS")
			(effects
				(font
					(size 0.4064 0.254)
					(thickness 0.1524)
				)
				(justify left)
			)
		)
		(property "Value" ""
			(at 0 0 270)
			(layer "F.Fab")
			(effects
				(font
					(size 1.27 1.27)
				)
			)
		)
		(duplicate_pad_numbers_are_jumpers no)
		(fp_poly
			(pts
				(xy 0.3048 -0.1016) (xy 0.3048 0.9906) (xy -0.3048 0.9906) (xy -0.3048 -0.1016)
			)
			(stroke
				(width 0)
				(type default)
			)
			(fill no)
			(layer "F.CrtYd")
		)
		(fp_line
			(start -0.3048 0.9906)
			(end 0.3048 0.9906)
			(stroke
				(width 0.1)
				(type default)
			)
			(layer "F.Fab")
		)
		(fp_line
			(start 0.3048 0.9906)
			(end 0.3048 -0.1016)
			(stroke
				(width 0.1)
				(type default)
			)
			(layer "F.Fab")
		)
		(fp_line
			(start -0.3048 -0.1016)
			(end -0.3048 0.9906)
			(stroke
				(width 0.1)
				(type default)
			)
			(layer "F.Fab")
		)
		(fp_line
			(start 0.3048 -0.1016)
			(end -0.3048 -0.1016)
			(stroke
				(width 0.1)
				(type default)
			)
			(layer "F.Fab")
		)
		(pad "1" smd rect
			(at 0 0 270)
			(size 0.508 0.508)
			(layers "F.Cu" "F.Mask" "F.Paste")
			(net "VR_PVCCIN_CPU0_PHASE2")
		)
		(pad "2" smd rect
			(at 0 0.889 270)
			(size 0.508 0.508)
			(layers "F.Cu" "F.Mask" "F.Paste")
			(net "VR_PVCCIN_CPU0_PHASE2_RC")
		)
		(zone
			(layer "F.Cu")
			(hatch none 0.5)
			(connect_pads
				(clearance 0)
			)
			(min_thickness 0.25)
			(keepout
				(tracks not_allowed)
				(vias allowed)
				(pads allowed)
				(copperpour not_allowed)
				(footprints allowed)
			)
			(placement
				(enabled no)
				(sheetname "")
			)
			(fill
				(thermal_gap 0.5)
				(thermal_bridge_width 0.5)
				(island_removal_mode 0)
			)
			(polygon
				(pts
					(xy 204.2414 -61.468) (xy 204.2414 -60.96) (xy 204.6224 -60.96) (xy 204.6224 -61.468)
				)
			)
		)
		(zone
			(layer "F.Cu")
			(hatch none 0.5)
			(connect_pads
				(clearance 0)
			)
			(min_thickness 0.25)
			(keepout
				(tracks allowed)
				(vias not_allowed)
				(pads allowed)
				(copperpour not_allowed)
				(footprints allowed)
			)
			(placement
				(enabled no)
				(sheetname "")
			)
			(fill
				(thermal_gap 0.5)
				(thermal_bridge_width 0.5)
				(island_removal_mode 0)
			)
			(polygon
				(pts
					(xy 204.6224 -61.468) (xy 204.6224 -60.96) (xy 204.2414 -60.96) (xy 204.2414 -61.468)
				)
			)
		)
	)
	(footprint ""
		(layer "F.Cu")
		(at 472.948 -144.7165)
		(property "Reference" "R9A16"
			(at 0 0 0)
			(layer "F.SilkS")
			(hide yes)
			(effects
				(font
					(size 1.27 1.27)
				)
			)
		)
		(property "Value" ""
			(at 0 0 0)
			(layer "F.Fab")
			(effects
				(font
					(size 1.27 1.27)
				)
			)
		)
		(duplicate_pad_numbers_are_jumpers no)
		(fp_poly
			(pts
				(xy -0.2794 -0.1016) (xy 0.2794 -0.1016) (xy 0.2794 0.9906) (xy -0.2794 0.9906)
			)
			(stroke
				(width 0)
				(type default)
			)
			(fill no)
			(layer "F.CrtYd")
		)
		(fp_line
			(start -0.2794 -0.1016)
			(end -0.2794 0.9906)
			(stroke
				(width 0.1)
				(type default)
			)
			(layer "F.Fab")
		)
		(fp_line
			(start -0.2794 0.9906)
			(end 0.2794 0.9906)
			(stroke
				(width 0.1)
				(type default)
			)
			(layer "F.Fab")
		)
		(fp_line
			(start 0.2794 -0.1016)
			(end -0.2794 -0.1016)
			(stroke
				(width 0.1)
				(type default)
			)
			(layer "F.Fab")
		)
		(fp_line
			(start 0.2794 0.9906)
			(end 0.2794 -0.1016)
			(stroke
				(width 0.1)
				(type default)
			)
			(layer "F.Fab")
		)
		(pad "1" smd rect
			(at 0 0)
			(size 0.508 0.508)
			(layers "F.Cu" "F.Mask" "F.Paste")
			(net "PU_KEY_CONN_PIN2_R")
		)
		(pad "2" smd rect
			(at 0 0.889)
			(size 0.508 0.508)
			(layers "F.Cu" "F.Mask" "F.Paste")
			(net "P3V3_STBY")
		)
		(zone
			(layer "F.Cu")
			(hatch none 0.5)
			(connect_pads
				(clearance 0)
			)
			(min_thickness 0.25)
			(keepout
				(tracks allowed)
				(vias not_allowed)
				(pads allowed)
				(copperpour not_allowed)
				(footprints allowed)
			)
			(placement
				(enabled no)
				(sheetname "")
			)
			(fill
				(thermal_gap 0.5)
				(thermal_bridge_width 0.5)
				(island_removal_mode 0)
			)
			(polygon
				(pts
					(xy 472.694 -144.4625) (xy 473.202 -144.4625) (xy 473.202 -144.0815) (xy 472.694 -144.0815)
				)
			)
		)
		(zone
			(layer "F.Cu")
			(hatch none 0.5)
			(connect_pads
				(clearance 0)
			)
			(min_thickness 0.25)
			(keepout
				(tracks not_allowed)
				(vias allowed)
				(pads allowed)
				(copperpour not_allowed)
				(footprints allowed)
			)
			(placement
				(enabled no)
				(sheetname "")
			)
			(fill
				(thermal_gap 0.5)
				(thermal_bridge_width 0.5)
				(island_removal_mode 0)
			)
			(polygon
				(pts
					(xy 472.694 -144.0815) (xy 473.202 -144.0815) (xy 473.202 -144.4625) (xy 472.694 -144.4625)
				)
			)
		)
	)
)
